#ISCELL
  mstr_misc dns *
  *
#ISCELL
  pure_quanta quanta_title_block_c *
  *
#ISCELL
  logical_power universal_power *
  page161_i100
#CELL
  pure_quanta q_res *
  page161_i101
#CELL
  pure_quanta q_res *
  page161_i102
#ISCELL
  logical_power universal_gnd *
  page161_i103
#CELL
  pure_quanta q_cap *
  page161_i104
#ISCELL
  logical_power universal_gnd *
  page161_i105
#ISCELL
  logical_power universal_gnd *
  page161_i106
#CELL
  pure_quanta q_res *
  page161_i107
#CELL
  pure_quanta q_res *
  page161_i108
#CELL
  pure_quanta q_res *
  page161_i109
#ISCELL
  standard offpage *
  page161_i110
#ISCELL
  standard offpage *
  page161_i111
#ISCELL
  standard offpage *
  page161_i112
#ISCELL
  standard offpage *
  page161_i113
#CELL
  pure_quanta q_res *
  page161_i114
#CELL
  pure_quanta q_res *
  page161_i115
#CELL
  pure_quanta q_res *
  page161_i116
#ISCELL
  logical_power universal_gnd *
  page161_i117
#ISCELL
  logical_power universal_gnd *
  page161_i118
#CELL
  pure_quanta q_cap *
  page161_i119
#ISCELL
  logical_power universal_gnd *
  page161_i120
#CELL
  pure_quanta q_res *
  page161_i121
#CELL
  pure_quanta q_res *
  page161_i122
#ISCELL
  logical_power universal_power *
  page161_i123
#ISCELL
  logical_power universal_gnd *
  page161_i124
#CELL
  pure_quanta q_res *
  page161_i125
#ISCELL
  logical_power universal_gnd *
  page161_i126
#CELL
  pure_quanta q_res *
  page161_i127
#CELL
  pure_quanta q_res *
  page161_i128
#CELL
  pure_quanta q_res *
  page161_i129
#ISCELL
  logical_power universal_power *
  page161_i130
#ISCELL
  standard offpage *
  page161_i132
#ISCELL
  standard offpage *
  page161_i133
#CELL
  pure_quanta q_res *
  page161_i134
#CELL
  pure_quanta q_res *
  page161_i135
#CELL
  pure_quanta q_res *
  page161_i136
#ISCELL
  logical_power universal_gnd *
  page161_i137
#ISCELL
  logical_power universal_gnd *
  page161_i138
#CELL
  pure_quanta q_cap *
  page161_i139
#ISCELL
  logical_power universal_gnd *
  page161_i140
#CELL
  pure_quanta q_res *
  page161_i141
#CELL
  pure_quanta q_res *
  page161_i142
#ISCELL
  logical_power universal_power *
  page161_i143
#ISCELL
  logical_power universal_gnd *
  page161_i144
#CELL
  pure_quanta q_res *
  page161_i145
#ISCELL
  logical_power universal_gnd *
  page161_i146
#CELL
  pure_quanta q_res *
  page161_i147
#CELL
  pure_quanta q_res *
  page161_i148
#CELL
  pure_quanta q_res *
  page161_i149
#ISCELL
  logical_power universal_power *
  page161_i15
#ISCELL
  logical_power universal_power *
  page161_i150
#ISCELL
  logical_power universal_power *
  page161_i153
#ISCELL
  logical_power universal_power *
  page161_i154
#ISCELL
  logical_power universal_power *
  page161_i156
#ISCELL
  logical_power universal_power *
  page161_i159
#CELL
  pure_quanta q_cap *
  page161_i16
#ISCELL
  standard offpage *
  page161_i160
#ISCELL
  standard offpage *
  page161_i161
#ISCELL
  standard offpage *
  page161_i162
#ISCELL
  standard offpage *
  page161_i163
#CELL
  pure_quanta lm75bd *
  page161_i164
#CELL
  pure_quanta lm75bd *
  page161_i165
#CELL
  pure_quanta lm75bd *
  page161_i166
#CELL
  pure_quanta lm75bd *
  page161_i167
#CELL
  pure_quanta q_res *
  page161_i168
#CELL
  pure_quanta q_res *
  page161_i169
#ISCELL
  logical_power universal_gnd *
  page161_i17
#CELL
  pure_quanta q_res *
  page161_i170
#CELL
  pure_quanta q_res *
  page161_i171
#ISCELL
  logical_power universal_gnd *
  page161_i21
#ISCELL
  standard offpage *
  page161_i75
#ISCELL
  standard offpage *
  page161_i76
#CELL
  pure_quanta q_res *
  page161_i77
#CELL
  pure_quanta q_res *
  page161_i78
#CELL
  pure_quanta q_res *
  page161_i79
#ISCELL
  logical_power universal_gnd *
  page161_i80
#CELL
  pure_quanta q_res *
  page161_i81
#CELL
  pure_quanta q_res *
  page161_i82
#ISCELL
  logical_power universal_power *
  page161_i83
#ISCELL
  logical_power universal_gnd *
  page161_i84
#CELL
  pure_quanta q_res *
  page161_i85
#CELL
  pure_quanta q_res *
  page161_i86
#CELL
  pure_quanta q_res *
  page161_i89
#ISCELL
  logical_power universal_gnd *
  page161_i90
#CELL
  pure_quanta q_res *
  page161_i91
#ISCELL
  logical_power universal_power *
  page161_i93
#CELL
  pure_quanta q_res *
  page161_i94
#CELL
  pure_quanta q_res *
  page161_i95
#CELL
  pure_quanta q_res *
  page161_i96
#ISCELL
  logical_power universal_gnd *
  page161_i97
#CELL
  pure_quanta q_res *
  page161_i98
#ISCELL
  logical_power universal_gnd *
  page161_i99
